(kicad_pcb
	(version 20260206)
	(generator "pcbnew")
	(generator_version "10.0")
	(general
		(thickness 1.6)
		(legacy_teardrops no)
	)
	(paper "A4")
	(title_block
		(title "v1-chassis-manager — T6M_CM_d_v01_1031_1645.brd")
		(comment 1 "Open CloudServer (Microsoft) / footprints 855-863 of 2512")
	)
	(layers
		(0 "F.Cu" signal "TOP")
		(4 "In1.Cu" signal "GND1")
		(6 "In2.Cu" signal "IN1")
		(8 "In3.Cu" signal "VCC1")
		(10 "In4.Cu" signal "VCC2")
		(12 "In5.Cu" signal "GND2")
		(14 "In6.Cu" signal "IN2")
		(16 "In7.Cu" signal "IN3")
		(18 "In8.Cu" signal "GND3")
		(2 "B.Cu" signal "BOTTOM")
		(9 "F.Adhes" user "F.Adhesive")
		(11 "B.Adhes" user "B.Adhesive")
		(13 "F.Paste" user "Package Geometry/Pastemask Top")
		(15 "B.Paste" user "Package Geometry/Pastemask Bottom")
		(5 "F.SilkS" user "Ref Des/Silkscreen Top")
		(7 "B.SilkS" user "Ref Des/Silkscreen Bottom")
		(1 "F.Mask" user "Board Geometry/Soldermask Top")
		(3 "B.Mask" user "Board Geometry/Soldermask Bottom")
		(17 "Dwgs.User" user "User.Drawings")
		(19 "Cmts.User" user "User.Comments")
		(21 "Eco1.User" user "User.Eco1")
		(23 "Eco2.User" user "User.Eco2")
		(25 "Edge.Cuts" user "Board Geometry/Outline")
		(27 "Margin" user)
		(31 "F.CrtYd" user "Package Geometry/Place Bound Top")
		(29 "B.CrtYd" user "Package Geometry/Place Bound Bottom")
		(35 "F.Fab" user "Ref Des/Assembly Top")
		(33 "B.Fab" user "Ref Des/Assembly Bottom")
	)
	(footprint ""
		(layer "F.Cu")
		(at 179.415694 -134.42442 -90)
		(property "Reference" "Q25"
			(at 2.223262 -14.328902 90)
			(unlocked yes)
			(layer "F.SilkS")
			(effects
				(font
					(size 0.7874 0.5842)
					(thickness 0.1524)
				)
				(justify left)
			)
		)
		(property "Value" ""
			(at 0 0 270)
			(layer "F.Fab")
			(effects
				(font
					(size 1.27 1.27)
				)
			)
		)
		(duplicate_pad_numbers_are_jumpers no)
		(fp_line
			(start -0.5842 2.48412)
			(end -0.5842 -0.5842)
			(stroke
				(width 0.1524)
				(type default)
			)
			(layer "F.SilkS")
		)
		(fp_line
			(start 2.584196 2.48412)
			(end -0.5842 2.48412)
			(stroke
				(width 0.1524)
				(type default)
			)
			(layer "F.SilkS")
		)
		(fp_line
			(start -0.5842 -0.5842)
			(end 2.584196 -0.5842)
			(stroke
				(width 0.1524)
				(type default)
			)
			(layer "F.SilkS")
		)
		(fp_line
			(start 2.584196 -0.5842)
			(end 2.584196 2.48412)
			(stroke
				(width 0.1524)
				(type default)
			)
			(layer "F.SilkS")
		)
		(fp_poly
			(pts
				(xy -0.508 -0.4572) (xy 0.299974 -0.4572) (xy 0.299974 -0.54991) (xy 1.700022 -0.54991) (xy 1.700022 0.49276)
				(xy 2.507996 0.49276) (xy 2.507996 1.40716) (xy 1.700022 1.40716) (xy 1.700022 2.450084) (xy 0.299974 2.450084)
				(xy 0.299974 2.35712) (xy -0.508 2.35712)
			)
			(stroke
				(width 0)
				(type default)
			)
			(fill no)
			(layer "F.CrtYd")
		)
		(fp_line
			(start 0.299974 2.450084)
			(end 0.299974 -0.54991)
			(stroke
				(width 0.1)
				(type default)
			)
			(layer "F.Fab")
		)
		(fp_line
			(start 1.700022 2.450084)
			(end 0.299974 2.450084)
			(stroke
				(width 0.1)
				(type default)
			)
			(layer "F.Fab")
		)
		(fp_line
			(start 0.299974 -0.54991)
			(end 1.700022 -0.54991)
			(stroke
				(width 0.1)
				(type default)
			)
			(layer "F.Fab")
		)
		(fp_line
			(start 1.700022 -0.54991)
			(end 1.700022 2.450084)
			(stroke
				(width 0.1)
				(type default)
			)
			(layer "F.Fab")
		)
		(fp_text user "E"
			(at -1.159764 1.751838 90)
			(unlocked yes)
			(layer "F.SilkS")
			(effects
				(font
					(size 0.635 0.4064)
					(thickness 0.1524)
				)
				(justify left)
			)
		)
		(fp_text user "C"
			(at 3.179572 0.787146 90)
			(unlocked yes)
			(layer "F.SilkS")
			(effects
				(font
					(size 0.635 0.4064)
					(thickness 0.1524)
				)
				(justify left)
			)
		)
		(fp_text user "B"
			(at -1.59258 -0.594614 0)
			(unlocked yes)
			(layer "F.SilkS")
			(effects
				(font
					(size 0.635 0.4064)
					(thickness 0.1524)
				)
				(justify left)
			)
		)
		(fp_text user "E"
			(at -1.5748 1.95707 270)
			(unlocked yes)
			(layer "F.Fab")
			(effects
				(font
					(size 0.7874 0.5842)
					(thickness 0.000001)
				)
				(justify left)
			)
		)
		(fp_text user "C"
			(at 2.8702 0.99187 270)
			(unlocked yes)
			(layer "F.Fab")
			(effects
				(font
					(size 0.7874 0.5842)
					(thickness 0.000001)
				)
				(justify left)
			)
		)
		(fp_text user "B"
			(at -1.5494 0.00127 270)
			(unlocked yes)
			(layer "F.Fab")
			(effects
				(font
					(size 0.7874 0.5842)
					(thickness 0.000001)
				)
				(justify left)
			)
		)
		(pad "B" smd rect
			(at 0 0)
			(size 0.8128 0.9144)
			(layers "F.Cu" "F.Mask" "F.Paste")
			(net "FM_CPLD_NODE1_WDT_R")
		)
		(pad "C" smd rect
			(at 1.999996 0.94996)
			(size 0.8128 0.9144)
			(layers "F.Cu" "F.Mask" "F.Paste")
			(net "FM_CPLD_NODE1_WDT")
		)
		(pad "E" smd rect
			(at 0 1.89992)
			(size 0.8128 0.9144)
			(layers "F.Cu" "F.Mask" "F.Paste")
			(net "FM_CPU_NODE1_OWDTOUT")
		)
	)
	(footprint ""
		(layer "F.Cu")
		(at 157.58668 -102.121208 180)
		(property "Reference" "C363"
			(at 1.524 -2.075688 0)
			(unlocked yes)
			(layer "F.SilkS")
			(effects
				(font
					(size 0.7874 0.5842)
					(thickness 0.1524)
				)
				(justify left)
			)
		)
		(property "Value" ""
			(at 0 0 180)
			(layer "F.Fab")
			(effects
				(font
					(size 1.27 1.27)
				)
			)
		)
		(duplicate_pad_numbers_are_jumpers no)
		(fp_line
			(start 0.7874 0.4064)
			(end -0.7874 0.4064)
			(stroke
				(width 0.1524)
				(type default)
			)
			(layer "F.SilkS")
		)
		(fp_line
			(start 0.7874 -0.4064)
			(end 0.7874 0.4064)
			(stroke
				(width 0.1524)
				(type default)
			)
			(layer "F.SilkS")
		)
		(fp_line
			(start 0 0.381)
			(end 0 -0.381)
			(stroke
				(width 0.1524)
				(type default)
			)
			(layer "F.SilkS")
		)
		(fp_line
			(start -0.7874 0.4064)
			(end -0.7874 -0.4064)
			(stroke
				(width 0.1524)
				(type default)
			)
			(layer "F.SilkS")
		)
		(fp_line
			(start -0.7874 -0.4064)
			(end 0.7874 -0.4064)
			(stroke
				(width 0.1524)
				(type default)
			)
			(layer "F.SilkS")
		)
		(fp_poly
			(pts
				(xy -0.5334 0.254) (xy -0.635 0.254) (xy -0.635 0.2286) (xy -0.635 -0.254) (xy -0.5334 -0.254) (xy -0.5334 -0.2794)
				(xy 0.5334 -0.2794) (xy 0.5334 -0.254) (xy 0.635 -0.254) (xy 0.635 0.254) (xy 0.5334 0.254) (xy 0.5334 0.2794)
				(xy -0.508 0.2794) (xy -0.5334 0.2794)
			)
			(stroke
				(width 0)
				(type default)
			)
			(fill no)
			(layer "F.CrtYd")
		)
		(pad "1" smd rect
			(at 0.40005 0 180)
			(size 0.4572 0.508)
			(layers "F.Cu" "F.Mask" "F.Paste")
			(net "P2E_CPU_USB_NODE1_RX_DP")
		)
		(pad "2" smd rect
			(at -0.40005 0 180)
			(size 0.4572 0.508)
			(layers "F.Cu" "F.Mask" "F.Paste")
			(net "P2E_CPU_USB_NODE1_RX_C_DP")
		)
	)
	(footprint ""
		(layer "F.Cu")
		(at 148.261578 -57.249822 -90)
		(property "Reference" "R514"
			(at -14.50213 -26.0858 90)
			(unlocked yes)
			(layer "F.SilkS")
			(effects
				(font
					(size 0.7874 0.5842)
					(thickness 0.1524)
				)
				(justify left)
			)
		)
		(property "Value" ""
			(at 0 0 270)
			(layer "F.Fab")
			(effects
				(font
					(size 1.27 1.27)
				)
			)
		)
		(duplicate_pad_numbers_are_jumpers no)
		(fp_line
			(start -0.7874 0.4064)
			(end -0.7874 -0.4064)
			(stroke
				(width 0.1524)
				(type default)
			)
			(layer "F.SilkS")
		)
		(fp_line
			(start 0.7874 0.4064)
			(end -0.7874 0.4064)
			(stroke
				(width 0.1524)
				(type default)
			)
			(layer "F.SilkS")
		)
		(fp_line
			(start -0.7874 -0.4064)
			(end 0.7874 -0.4064)
			(stroke
				(width 0.1524)
				(type default)
			)
			(layer "F.SilkS")
		)
		(fp_line
			(start 0.7874 -0.4064)
			(end 0.7874 0.4064)
			(stroke
				(width 0.1524)
				(type default)
			)
			(layer "F.SilkS")
		)
		(fp_poly
			(pts
				(xy -0.508 0.2794) (xy -0.508 0.2286) (xy -0.635 0.2286) (xy -0.635 -0.254) (xy -0.5334 -0.254)
				(xy -0.5334 -0.2794) (xy 0.5334 -0.2794) (xy 0.5334 -0.254) (xy 0.635 -0.254) (xy 0.635 0.254) (xy 0.5334 0.254)
				(xy 0.5334 0.2794)
			)
			(stroke
				(width 0)
				(type default)
			)
			(fill no)
			(layer "F.CrtYd")
		)
		(pad "1" smd rect
			(at 0.40005 0 270)
			(size 0.4572 0.508)
			(layers "F.Cu" "F.Mask" "F.Paste")
			(net "P3V3_NODE1")
		)
		(pad "2" smd rect
			(at -0.40005 0 270)
			(size 0.4572 0.508)
			(layers "F.Cu" "F.Mask" "F.Paste")
			(net "SATA_NODE1_GPIO3")
		)
	)
	(footprint ""
		(layer "F.Cu")
		(at 142.22476 -185.205624 -90)
		(property "Reference" "R1002"
			(at -4.768088 0.535432 90)
			(unlocked yes)
			(layer "F.SilkS")
			(effects
				(font
					(size 0.7874 0.5842)
					(thickness 0.1524)
				)
				(justify left)
			)
		)
		(property "Value" ""
			(at 0 0 270)
			(layer "F.Fab")
			(effects
				(font
					(size 1.27 1.27)
				)
			)
		)
		(duplicate_pad_numbers_are_jumpers no)
		(fp_line
			(start -0.7874 0.4064)
			(end -0.7874 -0.4064)
			(stroke
				(width 0.1524)
				(type default)
			)
			(layer "F.SilkS")
		)
		(fp_line
			(start 0.7874 0.4064)
			(end -0.7874 0.4064)
			(stroke
				(width 0.1524)
				(type default)
			)
			(layer "F.SilkS")
		)
		(fp_line
			(start -0.7874 -0.4064)
			(end 0.7874 -0.4064)
			(stroke
				(width 0.1524)
				(type default)
			)
			(layer "F.SilkS")
		)
		(fp_line
			(start 0.7874 -0.4064)
			(end 0.7874 0.4064)
			(stroke
				(width 0.1524)
				(type default)
			)
			(layer "F.SilkS")
		)
		(fp_poly
			(pts
				(xy -0.508 0.2794) (xy -0.508 0.2286) (xy -0.635 0.2286) (xy -0.635 -0.254) (xy -0.5334 -0.254)
				(xy -0.5334 -0.2794) (xy 0.5334 -0.2794) (xy 0.5334 -0.254) (xy 0.635 -0.254) (xy 0.635 0.254) (xy 0.5334 0.254)
				(xy 0.5334 0.2794)
			)
			(stroke
				(width 0)
				(type default)
			)
			(fill no)
			(layer "F.CrtYd")
		)
		(pad "1" smd rect
			(at 0.40005 0 270)
			(size 0.4572 0.508)
			(layers "F.Cu" "F.Mask" "F.Paste")
			(net "UART_T12_NODE4_TXD")
		)
		(pad "2" smd rect
			(at -0.40005 0 270)
			(size 0.4572 0.508)
			(layers "F.Cu" "F.Mask" "F.Paste")
			(net "UART_T12_NODE4_TXD_R")
		)
	)
	(footprint ""
		(layer "F.Cu")
		(at 106.28376 -188.126624 90)
		(property "Reference" "C699"
			(at 5.151882 0.764794 90)
			(unlocked yes)
			(layer "F.SilkS")
			(effects
				(font
					(size 0.7874 0.5842)
					(thickness 0.1524)
				)
				(justify left)
			)
		)
		(property "Value" ""
			(at 0 0 90)
			(layer "F.Fab")
			(effects
				(font
					(size 1.27 1.27)
				)
			)
		)
		(duplicate_pad_numbers_are_jumpers no)
		(fp_line
			(start 0.7874 -0.4064)
			(end 0.7874 0.4064)
			(stroke
				(width 0.1524)
				(type default)
			)
			(layer "F.SilkS")
		)
		(fp_line
			(start -0.7874 -0.4064)
			(end 0.7874 -0.4064)
			(stroke
				(width 0.1524)
				(type default)
			)
			(layer "F.SilkS")
		)
		(fp_line
			(start 0 0.381)
			(end 0 -0.381)
			(stroke
				(width 0.1524)
				(type default)
			)
			(layer "F.SilkS")
		)
		(fp_line
			(start 0.7874 0.4064)
			(end -0.7874 0.4064)
			(stroke
				(width 0.1524)
				(type default)
			)
			(layer "F.SilkS")
		)
		(fp_line
			(start -0.7874 0.4064)
			(end -0.7874 -0.4064)
			(stroke
				(width 0.1524)
				(type default)
			)
			(layer "F.SilkS")
		)
		(fp_poly
			(pts
				(xy -0.5334 0.254) (xy -0.635 0.254) (xy -0.635 0.2286) (xy -0.635 -0.254) (xy -0.5334 -0.254) (xy -0.5334 -0.2794)
				(xy 0.5334 -0.2794) (xy 0.5334 -0.254) (xy 0.635 -0.254) (xy 0.635 0.254) (xy 0.5334 0.254) (xy 0.5334 0.2794)
				(xy -0.508 0.2794) (xy -0.5334 0.2794)
			)
			(stroke
				(width 0)
				(type default)
			)
			(fill no)
			(layer "F.CrtYd")
		)
		(pad "1" smd rect
			(at 0.40005 0 90)
			(size 0.4572 0.508)
			(layers "F.Cu" "F.Mask" "F.Paste")
			(net "UART_T6_NODE1_TXD_R")
		)
		(pad "2" smd rect
			(at -0.40005 0 90)
			(size 0.4572 0.508)
			(layers "F.Cu" "F.Mask" "F.Paste")
			(net "GND")
		)
	)
	(footprint ""
		(layer "F.Cu")
		(at 79.10576 -188.126624 90)
		(property "Reference" "C667"
			(at 4.548886 -1.622298 90)
			(unlocked yes)
			(layer "F.SilkS")
			(effects
				(font
					(size 0.7874 0.5842)
					(thickness 0.1524)
				)
				(justify left)
			)
		)
		(property "Value" ""
			(at 0 0 90)
			(layer "F.Fab")
			(effects
				(font
					(size 1.27 1.27)
				)
			)
		)
		(duplicate_pad_numbers_are_jumpers no)
		(fp_line
			(start 0.7874 -0.4064)
			(end 0.7874 0.4064)
			(stroke
				(width 0.1524)
				(type default)
			)
			(layer "F.SilkS")
		)
		(fp_line
			(start -0.7874 -0.4064)
			(end 0.7874 -0.4064)
			(stroke
				(width 0.1524)
				(type default)
			)
			(layer "F.SilkS")
		)
		(fp_line
			(start 0 0.381)
			(end 0 -0.381)
			(stroke
				(width 0.1524)
				(type default)
			)
			(layer "F.SilkS")
		)
		(fp_line
			(start 0.7874 0.4064)
			(end -0.7874 0.4064)
			(stroke
				(width 0.1524)
				(type default)
			)
			(layer "F.SilkS")
		)
		(fp_line
			(start -0.7874 0.4064)
			(end -0.7874 -0.4064)
			(stroke
				(width 0.1524)
				(type default)
			)
			(layer "F.SilkS")
		)
		(fp_poly
			(pts
				(xy -0.5334 0.254) (xy -0.635 0.254) (xy -0.635 0.2286) (xy -0.635 -0.254) (xy -0.5334 -0.254) (xy -0.5334 -0.2794)
				(xy 0.5334 -0.2794) (xy 0.5334 -0.254) (xy 0.635 -0.254) (xy 0.635 0.254) (xy 0.5334 0.254) (xy 0.5334 0.2794)
				(xy -0.508 0.2794) (xy -0.5334 0.2794)
			)
			(stroke
				(width 0)
				(type default)
			)
			(fill no)
			(layer "F.CrtYd")
		)
		(pad "1" smd rect
			(at 0.40005 0 90)
			(size 0.4572 0.508)
			(layers "F.Cu" "F.Mask" "F.Paste")
			(net "T4_NODE4_EN_R")
		)
		(pad "2" smd rect
			(at -0.40005 0 90)
			(size 0.4572 0.508)
			(layers "F.Cu" "F.Mask" "F.Paste")
			(net "GND")
		)
	)
	(footprint ""
		(layer "F.Cu")
		(at 66.875406 -4.601464 -90)
		(property "Reference" "PC52"
			(at 1.20396 1.716532 90)
			(unlocked yes)
			(layer "F.SilkS")
			(effects
				(font
					(size 0.7874 0.5842)
					(thickness 0.1524)
				)
				(justify left)
			)
		)
		(property "Value" ""
			(at 0 0 270)
			(layer "F.Fab")
			(effects
				(font
					(size 1.27 1.27)
				)
			)
		)
		(duplicate_pad_numbers_are_jumpers no)
		(fp_line
			(start -0.7874 0.4064)
			(end -0.7874 -0.4064)
			(stroke
				(width 0.1524)
				(type default)
			)
			(layer "F.SilkS")
		)
		(fp_line
			(start 0.7874 0.4064)
			(end -0.7874 0.4064)
			(stroke
				(width 0.1524)
				(type default)
			)
			(layer "F.SilkS")
		)
		(fp_line
			(start 0 0.381)
			(end 0 -0.381)
			(stroke
				(width 0.1524)
				(type default)
			)
			(layer "F.SilkS")
		)
		(fp_line
			(start -0.7874 -0.4064)
			(end 0.7874 -0.4064)
			(stroke
				(width 0.1524)
				(type default)
			)
			(layer "F.SilkS")
		)
		(fp_line
			(start 0.7874 -0.4064)
			(end 0.7874 0.4064)
			(stroke
				(width 0.1524)
				(type default)
			)
			(layer "F.SilkS")
		)
		(fp_poly
			(pts
				(xy -0.5334 0.254) (xy -0.635 0.254) (xy -0.635 0.2286) (xy -0.635 -0.254) (xy -0.5334 -0.254) (xy -0.5334 -0.2794)
				(xy 0.5334 -0.2794) (xy 0.5334 -0.254) (xy 0.635 -0.254) (xy 0.635 0.254) (xy 0.5334 0.254) (xy 0.5334 0.2794)
				(xy -0.508 0.2794) (xy -0.5334 0.2794)
			)
			(stroke
				(width 0)
				(type default)
			)
			(fill no)
			(layer "F.CrtYd")
		)
		(pad "1" smd rect
			(at 0.40005 0 270)
			(size 0.4572 0.508)
			(layers "F.Cu" "F.Mask" "F.Paste")
			(net "GND")
		)
		(pad "2" smd rect
			(at -0.40005 0 270)
			(size 0.4572 0.508)
			(layers "F.Cu" "F.Mask" "F.Paste")
			(net "P3V3_NODE1_SS")
		)
	)
	(footprint ""
		(layer "F.Cu")
		(at 156.445712 -103.99395 -90)
		(property "Reference" "R534"
			(at 0.801878 2.04089 90)
			(unlocked yes)
			(layer "F.SilkS")
			(effects
				(font
					(size 0.7874 0.5842)
					(thickness 0.1524)
				)
				(justify left)
			)
		)
		(property "Value" ""
			(at 0 0 270)
			(layer "F.Fab")
			(effects
				(font
					(size 1.27 1.27)
				)
			)
		)
		(duplicate_pad_numbers_are_jumpers no)
		(fp_line
			(start -0.7874 0.4064)
			(end -0.7874 -0.4064)
			(stroke
				(width 0.1524)
				(type default)
			)
			(layer "F.SilkS")
		)
		(fp_line
			(start 0.7874 0.4064)
			(end -0.7874 0.4064)
			(stroke
				(width 0.1524)
				(type default)
			)
			(layer "F.SilkS")
		)
		(fp_line
			(start -0.7874 -0.4064)
			(end 0.7874 -0.4064)
			(stroke
				(width 0.1524)
				(type default)
			)
			(layer "F.SilkS")
		)
		(fp_line
			(start 0.7874 -0.4064)
			(end 0.7874 0.4064)
			(stroke
				(width 0.1524)
				(type default)
			)
			(layer "F.SilkS")
		)
		(fp_poly
			(pts
				(xy -0.508 0.2794) (xy -0.508 0.2286) (xy -0.635 0.2286) (xy -0.635 -0.254) (xy -0.5334 -0.254)
				(xy -0.5334 -0.2794) (xy 0.5334 -0.2794) (xy 0.5334 -0.254) (xy 0.635 -0.254) (xy 0.635 0.254) (xy 0.5334 0.254)
				(xy 0.5334 0.2794)
			)
			(stroke
				(width 0)
				(type default)
			)
			(fill no)
			(layer "F.CrtYd")
		)
		(pad "1" smd rect
			(at 0.40005 0 270)
			(size 0.4572 0.508)
			(layers "F.Cu" "F.Mask" "F.Paste")
			(net "P3V3_NODE1")
		)
		(pad "2" smd rect
			(at -0.40005 0 270)
			(size 0.4572 0.508)
			(layers "F.Cu" "F.Mask" "F.Paste")
			(net "USB_WAKE_N")
		)
	)
	(footprint ""
		(layer "F.Cu")
		(at 35.802824 -84.339684)
		(property "Reference" "R108"
			(at -4.721606 0.049784 0)
			(unlocked yes)
			(layer "F.SilkS")
			(effects
				(font
					(size 0.7874 0.5842)
					(thickness 0.1524)
				)
				(justify left)
			)
		)
		(property "Value" ""
			(at 0 0 0)
			(layer "F.Fab")
			(effects
				(font
					(size 1.27 1.27)
				)
			)
		)
		(duplicate_pad_numbers_are_jumpers no)
		(fp_line
			(start -0.7874 -0.4064)
			(end 0.7874 -0.4064)
			(stroke
				(width 0.1524)
				(type default)
			)
			(layer "F.SilkS")
		)
		(fp_line
			(start -0.7874 0.4064)
			(end -0.7874 -0.4064)
			(stroke
				(width 0.1524)
				(type default)
			)
			(layer "F.SilkS")
		)
		(fp_line
			(start 0.7874 -0.4064)
			(end 0.7874 0.4064)
			(stroke
				(width 0.1524)
				(type default)
			)
			(layer "F.SilkS")
		)
		(fp_line
			(start 0.7874 0.4064)
			(end -0.7874 0.4064)
			(stroke
				(width 0.1524)
				(type default)
			)
			(layer "F.SilkS")
		)
		(fp_poly
			(pts
				(xy -0.508 0.2794) (xy -0.508 0.2286) (xy -0.635 0.2286) (xy -0.635 -0.254) (xy -0.5334 -0.254)
				(xy -0.5334 -0.2794) (xy 0.5334 -0.2794) (xy 0.5334 -0.254) (xy 0.635 -0.254) (xy 0.635 0.254) (xy 0.5334 0.254)
				(xy 0.5334 0.2794)
			)
			(stroke
				(width 0)
				(type default)
			)
			(fill no)
			(layer "F.CrtYd")
		)
		(pad "1" smd rect
			(at 0.40005 0)
			(size 0.4572 0.508)
			(layers "F.Cu" "F.Mask" "F.Paste")
			(net "PD_NODE1_NTB_PERN")
		)
		(pad "2" smd rect
			(at -0.40005 0)
			(size 0.4572 0.508)
			(layers "F.Cu" "F.Mask" "F.Paste")
			(net "GND")
		)
	)
)
